# S9S_MB_2U (Grand Teton) — schematic netlist excerpt (pin names and nets, part order shuffled) for the footprints in the layout excerpt that follows; sources: Cadence DE-HDL packaged netlist, KiCad conversion of 03242023_DA0F0TMBIJ0_F0T_Motherboard_J_brd_V01_OCP.brd

R4605  Q_RES  4.7K 5% CHIP  pkg 0402LF  page 224 : A = P3V3_AUX ; B = PWRGD_PS_PWROK_PLD_ISO

U257  74LVC2G07DW7  74LVC2G07DW-7 IC  pkg SOT363_0-65_2X1-25XC  page 150
  \1a\  = GPU_FPGA_EROT_RECOV_N
  GND  = GND
  \2a\  = GND
  \2y\  = NC_U257_2Y
  VCC  = P3V3_AUX
  \1y\  = GPU_FPGA_EROT_RECOV_BUF_R_N

(kicad_pcb
	(version 20260206)
	(generator "pcbnew")
	(generator_version "10.0")
	(general
		(thickness 1.6)
		(legacy_teardrops no)
	)
	(paper "A4")
	(title_block
		(title "03242023_DA0F0TMBIJ0_F0T_Motherboard_J_brd_V01_OCP.brd")
		(comment 1 "Grand Teton / footprints 1484-1485 of 6105")
	)
	(layers
		(0 "F.Cu" signal "TOP")
		(4 "In1.Cu" signal "GND")
		(6 "In2.Cu" signal "IN1")
		(8 "In3.Cu" signal "GND1")
		(10 "In4.Cu" signal "IN2")
		(12 "In5.Cu" signal "GND2")
		(14 "In6.Cu" signal "IN3")
		(16 "In7.Cu" signal "GND3")
		(18 "In8.Cu" signal "VCC")
		(20 "In9.Cu" signal "VCC1")
		(22 "In10.Cu" signal "GND4")
		(24 "In11.Cu" signal "IN4")
		(26 "In12.Cu" signal "GND5")
		(28 "In13.Cu" signal "IN5")
		(30 "In14.Cu" signal "GND6")
		(32 "In15.Cu" signal "IN6")
		(34 "In16.Cu" signal "GND7")
		(2 "B.Cu" signal "BOTTOM")
		(9 "F.Adhes" user "F.Adhesive")
		(11 "B.Adhes" user "B.Adhesive")
		(13 "F.Paste" user "Package Geometry/Pastemask Top")
		(15 "B.Paste" user "Package Geometry/Pastemask Bottom")
		(5 "F.SilkS" user "Ref Des/Silkscreen Top")
		(7 "B.SilkS" user "Ref Des/Silkscreen Bottom")
		(1 "F.Mask" user "Board Geometry/Soldermask Top")
		(3 "B.Mask" user "Board Geometry/Soldermask Bottom")
		(17 "Dwgs.User" user "User.Drawings")
		(19 "Cmts.User" user "User.Comments")
		(21 "Eco1.User" user "User.Eco1")
		(23 "Eco2.User" user "User.Eco2")
		(25 "Edge.Cuts" user "Board Geometry/Outline")
		(27 "Margin" user)
		(31 "F.CrtYd" user "Package Geometry/Place Bound Top")
		(29 "B.CrtYd" user "Package Geometry/Place Bound Bottom")
		(35 "F.Fab" user "Ref Des/Assembly Top")
		(33 "B.Fab" user "Ref Des/Assembly Bottom")
	)
	(footprint ""
		(layer "F.Cu")
		(at 150.622 -133.314948)
		(property "Reference" "R4605"
			(at 0 0 0)
			(layer "F.SilkS")
			(hide yes)
			(effects
				(font
					(size 1.27 1.27)
				)
			)
		)
		(property "Value" ""
			(at 0 0 0)
			(layer "F.Fab")
			(effects
				(font
					(size 1.27 1.27)
				)
			)
		)
		(duplicate_pad_numbers_are_jumpers no)
		(fp_line
			(start -0.7874 -0.4064)
			(end 0.7874 -0.4064)
			(stroke
				(width 0.1524)
				(type default)
			)
			(layer "F.SilkS")
		)
		(fp_line
			(start -0.7874 0.4064)
			(end -0.7874 -0.4064)
			(stroke
				(width 0.1524)
				(type default)
			)
			(layer "F.SilkS")
		)
		(fp_line
			(start 0.7874 -0.4064)
			(end 0.7874 0.4064)
			(stroke
				(width 0.1524)
				(type default)
			)
			(layer "F.SilkS")
		)
		(fp_line
			(start 0.7874 0.4064)
			(end -0.7874 0.4064)
			(stroke
				(width 0.1524)
				(type default)
			)
			(layer "F.SilkS")
		)
		(fp_line
			(start -0.67945 -0.305054)
			(end -0.12065 -0.305054)
			(stroke
				(width 0.1)
				(type default)
			)
			(layer "F.Fab")
		)
		(fp_line
			(start -0.67945 0.3048)
			(end -0.67945 -0.305054)
			(stroke
				(width 0.1)
				(type default)
			)
			(layer "F.Fab")
		)
		(fp_line
			(start -0.12065 -0.305054)
			(end -0.12065 -0.2794)
			(stroke
				(width 0.1)
				(type default)
			)
			(layer "F.Fab")
		)
		(fp_line
			(start -0.12065 -0.2794)
			(end 0.12065 -0.2794)
			(stroke
				(width 0.1)
				(type default)
			)
			(layer "F.Fab")
		)
		(fp_line
			(start -0.12065 0.2794)
			(end -0.12065 0.3048)
			(stroke
				(width 0.1)
				(type default)
			)
			(layer "F.Fab")
		)
		(fp_line
			(start -0.12065 0.3048)
			(end -0.67945 0.3048)
			(stroke
				(width 0.1)
				(type default)
			)
			(layer "F.Fab")
		)
		(fp_line
			(start 0.120396 0.2794)
			(end -0.12065 0.2794)
			(stroke
				(width 0.1)
				(type default)
			)
			(layer "F.Fab")
		)
		(fp_line
			(start 0.120396 0.3048)
			(end 0.120396 0.2794)
			(stroke
				(width 0.1)
				(type default)
			)
			(layer "F.Fab")
		)
		(fp_line
			(start 0.12065 -0.3048)
			(end 0.67945 -0.3048)
			(stroke
				(width 0.1)
				(type default)
			)
			(layer "F.Fab")
		)
		(fp_line
			(start 0.12065 -0.2794)
			(end 0.12065 -0.3048)
			(stroke
				(width 0.1)
				(type default)
			)
			(layer "F.Fab")
		)
		(fp_line
			(start 0.67945 -0.3048)
			(end 0.67945 0.3048)
			(stroke
				(width 0.1)
				(type default)
			)
			(layer "F.Fab")
		)
		(fp_line
			(start 0.67945 0.3048)
			(end 0.120396 0.3048)
			(stroke
				(width 0.1)
				(type default)
			)
			(layer "F.Fab")
		)
		(pad "1" smd circle
			(at -0.40005 0)
			(size 0 0)
			(layers "F.Cu" "F.Mask" "F.Paste")
			(net "P3V3_AUX")
		)
		(pad "2" smd circle
			(at 0.40005 0)
			(size 0 0)
			(layers "F.Cu" "F.Mask" "F.Paste")
			(net "PWRGD_PS_PWROK_PLD_ISO")
		)
	)
	(footprint ""
		(layer "F.Cu")
		(at 111.764826 -402.145246 90)
		(property "Reference" "U257"
			(at 1.622552 -4.533646 0)
			(unlocked yes)
			(layer "F.SilkS")
			(effects
				(font
					(size 0.7874 0.5842)
					(thickness 0.1524)
				)
				(justify left)
			)
		)
		(property "Value" ""
			(at 0 0 90)
			(layer "F.Fab")
			(effects
				(font
					(size 1.27 1.27)
				)
			)
		)
		(duplicate_pad_numbers_are_jumpers no)
		(fp_line
			(start 1.38176 -1.100074)
			(end 0.592074 -1.100074)
			(stroke
				(width 0.1524)
				(type default)
			)
			(layer "F.SilkS")
		)
		(fp_line
			(start 0.592074 -1.100074)
			(end 0 -0.508)
			(stroke
				(width 0.1524)
				(type default)
			)
			(layer "F.SilkS")
		)
		(fp_line
			(start -0.592074 -1.100074)
			(end -1.38176 -1.100074)
			(stroke
				(width 0.1524)
				(type default)
			)
			(layer "F.SilkS")
		)
		(fp_line
			(start -1.38176 -1.100074)
			(end -1.38176 1.100074)
			(stroke
				(width 0.1524)
				(type default)
			)
			(layer "F.SilkS")
		)
		(fp_line
			(start 0 -0.508)
			(end -0.592074 -1.100074)
			(stroke
				(width 0.1524)
				(type default)
			)
			(layer "F.SilkS")
		)
		(fp_line
			(start 1.38176 1.100074)
			(end 1.38176 -1.100074)
			(stroke
				(width 0.1524)
				(type default)
			)
			(layer "F.SilkS")
		)
		(fp_line
			(start -1.38176 1.100074)
			(end 1.38176 1.100074)
			(stroke
				(width 0.1524)
				(type default)
			)
			(layer "F.SilkS")
		)
		(fp_poly
			(pts
				(xy -1.50241 -0.649986) (xy -1.9431 -0.429768) (xy -1.9431 -0.870204)
			)
			(stroke
				(width 0)
				(type default)
			)
			(fill yes)
			(layer "F.SilkS")
		)
		(fp_line
			(start 0.674878 -1.100074)
			(end -0.674878 -1.100074)
			(stroke
				(width 0.1)
				(type default)
			)
			(layer "F.Fab")
		)
		(fp_line
			(start -0.674878 -1.100074)
			(end -0.674878 1.100074)
			(stroke
				(width 0.1)
				(type default)
			)
			(layer "F.Fab")
		)
		(fp_line
			(start 0.674878 1.100074)
			(end 0.674878 -1.100074)
			(stroke
				(width 0.1)
				(type default)
			)
			(layer "F.Fab")
		)
		(fp_line
			(start -0.674878 1.100074)
			(end 0.674878 1.100074)
			(stroke
				(width 0.1)
				(type default)
			)
			(layer "F.Fab")
		)
		(fp_poly
			(pts
				(xy -1.9431 -0.870204) (xy -1.50241 -0.649986) (xy -1.9431 -0.429768)
			)
			(stroke
				(width 0)
				(type default)
			)
			(fill yes)
			(layer "F.Fab")
		)
		(pad "1" smd rect
			(at -0.94996 -0.649986)
			(size 0.4318 0.6096)
			(layers "F.Cu" "F.Mask" "F.Paste")
			(net "GPU_FPGA_EROT_RECOV_N")
		)
		(pad "2" smd rect
			(at -0.94996 0)
			(size 0.4318 0.6096)
			(layers "F.Cu" "F.Mask" "F.Paste")
			(net "GND")
		)
		(pad "3" smd rect
			(at -0.94996 0.649986)
			(size 0.4318 0.6096)
			(layers "F.Cu" "F.Mask" "F.Paste")
			(net "GND")
		)
		(pad "4" smd rect
			(at 0.94996 0.649986)
			(size 0.4318 0.6096)
			(layers "F.Cu" "F.Mask" "F.Paste")
			(net "NC_U257_2Y")
		)
		(pad "5" smd rect
			(at 0.94996 0)
			(size 0.4318 0.6096)
			(layers "F.Cu" "F.Mask" "F.Paste")
			(net "P3V3_AUX")
		)
		(pad "6" smd rect
			(at 0.94996 -0.649986)
			(size 0.4318 0.6096)
			(layers "F.Cu" "F.Mask" "F.Paste")
			(net "GPU_FPGA_EROT_RECOV_BUF_R_N")
		)
	)
)
